(kicad_pcb
	(version 20241229)
	(generator "pcbnew")
	(generator_version "9.0")
	(general
		(thickness 1.61)
		(legacy_teardrops no)
	)
	(paper "A3")
	(title_block
		(title "RDIMM DDR5 Tester")
		(date "2026-05-21")
		(rev "2.2.0")
		(company "Antmicro")
		(comment 9 "footprints 118-118 of 796")
	)
	(layers
		(0 "F.Cu" signal)
		(4 "In1.Cu" power)
		(6 "In2.Cu" mixed)
		(8 "In3.Cu" power)
		(10 "In4.Cu" mixed)
		(12 "In5.Cu" power)
		(14 "In6.Cu" mixed)
		(16 "In7.Cu" power)
		(18 "In8.Cu" power)
		(20 "In9.Cu" mixed)
		(22 "In10.Cu" power)
		(2 "B.Cu" signal)
		(9 "F.Adhes" user "F.Adhesive")
		(11 "B.Adhes" user "B.Adhesive")
		(13 "F.Paste" user)
		(15 "B.Paste" user)
		(5 "F.SilkS" user "F.Silkscreen")
		(7 "B.SilkS" user "B.Silkscreen")
		(1 "F.Mask" user)
		(3 "B.Mask" user)
		(17 "Dwgs.User" user "User.Drawings")
		(19 "Cmts.User" user "User.Comments")
		(21 "Eco1.User" user "User.Eco1")
		(23 "Eco2.User" user "User.Eco2")
		(25 "Edge.Cuts" user)
		(27 "Margin" user)
		(31 "F.CrtYd" user "F.Courtyard")
		(29 "B.CrtYd" user "B.Courtyard")
		(35 "F.Fab" user)
		(33 "B.Fab" user)
	)
	(footprint "antmicro-footprints:Heatsink_ATS-61500R-C2-R0"
		(layer "F.Cu")
		(at 188.5 152.5)
		(property "Reference" "A1"
			(at 0.003 -27.94 0)
			(unlocked yes)
			(layer "F.SilkS")
			(hide yes)
			(effects
				(font
					(size 0.7 0.7)
					(thickness 0.15)
				)
				(justify left bottom)
			)
		)
		(property "Value" "Heatsink_ATS-61500R-C2-R0"
			(at 0.003 27.94 0)
			(unlocked yes)
			(layer "F.Fab")
			(effects
				(font
					(size 0.7 0.7)
					(thickness 0.15)
				)
				(justify left bottom)
			)
		)
		(property "Datasheet" "https://www.qats.com/DataSheet/ATS-61500-Series-C2-R0"
			(at 0 0 0)
			(layer "F.Fab")
			(hide yes)
			(effects
				(font
					(size 1.27 1.27)
					(thickness 0.15)
				)
			)
		)
		(property "MPN" "ATS-61500R-C2-R0"
			(at 0 0 0)
			(unlocked yes)
			(layer "F.Fab")
			(hide yes)
			(effects
				(font
					(size 1 1)
					(thickness 0.15)
				)
			)
		)
		(property "Manufacturer" "Advanced Thermal Solutions"
			(at 0 0 0)
			(unlocked yes)
			(layer "F.Fab")
			(hide yes)
			(effects
				(font
					(size 1 1)
					(thickness 0.15)
				)
			)
		)
		(property "Author" "Antmicro"
			(at 0 0 0)
			(unlocked yes)
			(layer "F.Fab")
			(hide yes)
			(effects
				(font
					(size 1 1)
					(thickness 0.15)
				)
			)
		)
		(property "License" "Apache-2.0"
			(at 0 0 0)
			(unlocked yes)
			(layer "F.Fab")
			(hide yes)
			(effects
				(font
					(size 1 1)
					(thickness 0.15)
				)
			)
		)
		(property ki_fp_filters "Heatsink_*")
		(sheetname "/")
		(sheetfile "data-center-rdimm-ddr5-tester.kicad_sch")
		(attr exclude_from_pos_files)
		(fp_circle
			(center -22 -22)
			(end -17.78 -22)
			(stroke
				(width 0.05)
				(type solid)
			)
			(fill no)
			(layer "F.CrtYd")
		)
		(fp_circle
			(center -22 22)
			(end -17.78 22)
			(stroke
				(width 0.05)
				(type solid)
			)
			(fill no)
			(layer "F.CrtYd")
		)
		(fp_circle
			(center 22 -22)
			(end 26.22 -22)
			(stroke
				(width 0.05)
				(type solid)
			)
			(fill no)
			(layer "F.CrtYd")
		)
		(fp_circle
			(center 22 22)
			(end 26.22 22)
			(stroke
				(width 0.05)
				(type solid)
			)
			(fill no)
			(layer "F.CrtYd")
		)
		(fp_text user "Author: Antmicro"
			(at -27.32 31.72 0)
			(layer "F.Fab")
			(effects
				(font
					(size 0.7 0.7)
					(thickness 0.15)
				)
				(justify left bottom)
			)
		)
		(fp_text user "${REFERENCE}"
			(at -27.32 30.52 0)
			(layer "F.Fab")
			(effects
				(font
					(size 0.7 0.7)
					(thickness 0.15)
				)
				(justify left bottom)
			)
		)
		(fp_text user "License: Apache-2.0"
			(at -27.32 29.32 0)
			(layer "F.Fab")
			(effects
				(font
					(size 0.7 0.7)
					(thickness 0.15)
				)
				(justify left bottom)
			)
		)
		(fp_text user "Suggested mounting holes diameter: 3.18 mm"
			(at -9.07 -0.18 0)
			(layer "F.Fab")
			(effects
				(font
					(size 0.7 0.7)
					(thickness 0.15)
				)
				(justify left bottom)
			)
		)
		(zone
			(net 0)
			(net_name "")
			(layers "F.Cu" "B.Cu" "In1.Cu" "In2.Cu" "In3.Cu" "In4.Cu" "In5.Cu" "In6.Cu"
				"In7.Cu" "In8.Cu" "In9.Cu" "In10.Cu"
			)
			(hatch edge 0.5)
			(connect_pads
				(clearance 0)
			)
			(min_thickness 0.25)
			(filled_areas_thickness no)
			(keepout
				(tracks not_allowed)
				(vias not_allowed)
				(pads allowed)
				(copperpour not_allowed)
				(footprints allowed)
			)
			(placement
				(enabled no)
				(sheetname "")
			)
			(fill
				(thermal_gap 0.5)
				(thermal_bridge_width 0.5)
			)
			(polygon
				(pts
					(xy 168.5 130.5) (xy 168.479643 130.21537) (xy 168.418986 129.936535) (xy 168.319264 129.66917)
					(xy 168.182507 129.418718) (xy 168.011499 129.190279) (xy 167.809721 128.988501) (xy 167.581282 128.817493)
					(xy 167.33083 128.680736) (xy 167.063465 128.581014) (xy 166.78463 128.520357) (xy 166.5 128.5)
					(xy 166.21537 128.520357) (xy 165.936535 128.581014) (xy 165.66917 128.680736) (xy 165.418718 128.817493)
					(xy 165.190279 128.988501) (xy 164.988501 129.190279) (xy 164.817493 129.418718) (xy 164.680736 129.66917)
					(xy 164.581014 129.936535) (xy 164.520357 130.21537) (xy 164.5 130.5) (xy 164.520357 130.78463)
					(xy 164.581014 131.063465) (xy 164.680736 131.33083) (xy 164.817493 131.581282) (xy 164.988501 131.809721)
					(xy 165.190279 132.011499) (xy 165.418718 132.182507) (xy 165.66917 132.319264) (xy 165.936535 132.418986)
					(xy 166.21537 132.479643) (xy 166.5 132.5) (xy 166.78463 132.479643) (xy 167.063465 132.418986)
					(xy 167.33083 132.319264) (xy 167.581282 132.182507) (xy 167.809721 132.011499) (xy 168.011499 131.809721)
					(xy 168.182507 131.581282) (xy 168.319264 131.33083) (xy 168.418986 131.063465) (xy 168.479643 130.78463)
				)
			)
		)
		(zone
			(net 0)
			(net_name "")
			(layers "F.Cu" "B.Cu" "In1.Cu" "In2.Cu" "In3.Cu" "In4.Cu" "In5.Cu" "In6.Cu"
				"In7.Cu" "In8.Cu" "In9.Cu" "In10.Cu"
			)
			(hatch edge 0.5)
			(connect_pads
				(clearance 0)
			)
			(min_thickness 0.25)
			(filled_areas_thickness no)
			(keepout
				(tracks not_allowed)
				(vias not_allowed)
				(pads allowed)
				(copperpour not_allowed)
				(footprints allowed)
			)
			(placement
				(enabled no)
				(sheetname "")
			)
			(fill
				(thermal_gap 0.5)
				(thermal_bridge_width 0.5)
			)
			(polygon
				(pts
					(xy 168.5 174.481014) (xy 168.479643 174.196384) (xy 168.418986 173.917549) (xy 168.319264 173.650184)
					(xy 168.182507 173.399732) (xy 168.011499 173.171293) (xy 167.809721 172.969515) (xy 167.581282 172.798507)
					(xy 167.33083 172.66175) (xy 167.063465 172.562028) (xy 166.78463 172.501371) (xy 166.5 172.481014)
					(xy 166.21537 172.501371) (xy 165.936535 172.562028) (xy 165.66917 172.66175) (xy 165.418718 172.798507)
					(xy 165.190279 172.969515) (xy 164.988501 173.171293) (xy 164.817493 173.399732) (xy 164.680736 173.650184)
					(xy 164.581014 173.917549) (xy 164.520357 174.196384) (xy 164.5 174.481014) (xy 164.520357 174.765644)
					(xy 164.581014 175.044479) (xy 164.680736 175.311844) (xy 164.817493 175.562296) (xy 164.988501 175.790735)
					(xy 165.190279 175.992513) (xy 165.418718 176.163521) (xy 165.66917 176.300278) (xy 165.936535 176.4)
					(xy 166.21537 176.460657) (xy 166.5 176.481014) (xy 166.78463 176.460657) (xy 167.063465 176.4)
					(xy 167.33083 176.300278) (xy 167.581282 176.163521) (xy 167.809721 175.992513) (xy 168.011499 175.790735)
					(xy 168.182507 175.562296) (xy 168.319264 175.311844) (xy 168.418986 175.044479) (xy 168.479643 174.765644)
				)
			)
		)
		(zone
			(net 0)
			(net_name "")
			(layers "F.Cu" "B.Cu" "In1.Cu" "In2.Cu" "In3.Cu" "In4.Cu" "In5.Cu" "In6.Cu"
				"In7.Cu" "In8.Cu" "In9.Cu" "In10.Cu"
			)
			(hatch edge 0.5)
			(connect_pads
				(clearance 0)
			)
			(min_thickness 0.25)
			(filled_areas_thickness no)
			(keepout
				(tracks not_allowed)
				(vias not_allowed)
				(pads allowed)
				(copperpour not_allowed)
				(footprints allowed)
			)
			(placement
				(enabled no)
				(sheetname "")
			)
			(fill
				(thermal_gap 0.5)
				(thermal_bridge_width 0.5)
			)
			(polygon
				(pts
					(xy 212.517493 174.481014) (xy 212.497136 174.196384) (xy 212.436479 173.917549) (xy 212.336757 173.650184)
					(xy 212.2 173.399732) (xy 212.028992 173.171293) (xy 211.827214 172.969515) (xy 211.598775 172.798507)
					(xy 211.348323 172.66175) (xy 211.080958 172.562028) (xy 210.802123 172.501371) (xy 210.517493 172.481014)
					(xy 210.232863 172.501371) (xy 209.954028 172.562028) (xy 209.686663 172.66175) (xy 209.436211 172.798507)
					(xy 209.207772 172.969515) (xy 209.005994 173.171293) (xy 208.834986 173.399732) (xy 208.698229 173.650184)
					(xy 208.598507 173.917549) (xy 208.53785 174.196384) (xy 208.517493 174.481014) (xy 208.53785 174.765644)
					(xy 208.598507 175.044479) (xy 208.698229 175.311844) (xy 208.834986 175.562296) (xy 209.005994 175.790735)
					(xy 209.207772 175.992513) (xy 209.436211 176.163521) (xy 209.686663 176.300278) (xy 209.954028 176.4)
					(xy 210.232863 176.460657) (xy 210.517493 176.481014) (xy 210.802123 176.460657) (xy 211.080958 176.4)
					(xy 211.348323 176.300278) (xy 211.598775 176.163521) (xy 211.827214 175.992513) (xy 212.028992 175.790735)
					(xy 212.2 175.562296) (xy 212.336757 175.311844) (xy 212.436479 175.044479) (xy 212.497136 174.765644)
				)
			)
		)
		(zone
			(net 0)
			(net_name "")
			(layers "F.Cu" "B.Cu" "In1.Cu" "In2.Cu" "In3.Cu" "In4.Cu" "In5.Cu" "In6.Cu"
				"In7.Cu" "In8.Cu" "In9.Cu" "In10.Cu"
			)
			(hatch edge 0.5)
			(connect_pads
				(clearance 0)
			)
			(min_thickness 0.25)
			(filled_areas_thickness no)
			(keepout
				(tracks not_allowed)
				(vias not_allowed)
				(pads allowed)
				(copperpour not_allowed)
				(footprints allowed)
			)
			(placement
				(enabled no)
				(sheetname "")
			)
			(fill
				(thermal_gap 0.5)
				(thermal_bridge_width 0.5)
			)
			(polygon
				(pts
					(xy 212.520357 130.48463) (xy 212.5 130.2) (xy 212.439343 129.921165) (xy 212.339621 129.6538)
					(xy 212.202864 129.403348) (xy 212.031856 129.174909) (xy 211.830078 128.973131) (xy 211.601639 128.802123)
					(xy 211.351187 128.665366) (xy 211.083822 128.565644) (xy 210.804987 128.504987) (xy 210.520357 128.48463)
					(xy 210.235727 128.504987) (xy 209.956892 128.565644) (xy 209.689527 128.665366) (xy 209.439075 128.802123)
					(xy 209.210636 128.973131) (xy 209.008858 129.174909) (xy 208.83785 129.403348) (xy 208.701093 129.6538)
					(xy 208.601371 129.921165) (xy 208.540714 130.2) (xy 208.520357 130.48463) (xy 208.540714 130.76926)
					(xy 208.601371 131.048095) (xy 208.701093 131.31546) (xy 208.83785 131.565912) (xy 209.008858 131.794351)
					(xy 209.210636 131.996129) (xy 209.439075 132.167137) (xy 209.689527 132.303894) (xy 209.956892 132.403616)
					(xy 210.235727 132.464273) (xy 210.520357 132.48463) (xy 210.804987 132.464273) (xy 211.083822 132.403616)
					(xy 211.351187 132.303894) (xy 211.601639 132.167137) (xy 211.830078 131.996129) (xy 212.031856 131.794351)
					(xy 212.202864 131.565912) (xy 212.339621 131.31546) (xy 212.439343 131.048095) (xy 212.5 130.76926)
				)
			)
		)
	)
)
